# T6G (Grand Teton) — schematic netlist excerpt (pin names and nets, part order shuffled) for the footprints in the layout excerpt that follows; sources: Cadence DE-HDL packaged netlist, KiCad conversion of 04192023_DAF0TMB3IC0_F0TG_MB_C_brd_V02_OCP.brd

C2589  Q_CAP  22UF 4V 20% X6S  pkg C0402  page 70 : A = PVDDCR_SOC_P0 ; B = GND
R2420  Q_RES  33.2 1% CHIP  pkg 0402LF  page 150 : A = SMB_CPU0_CPU1_APML_SDA ; B = SMB_CPU0_CPU1_APML_SDA_R

(kicad_pcb
	(version 20260206)
	(generator "pcbnew")
	(generator_version "10.0")
	(general
		(thickness 1.6)
		(legacy_teardrops no)
	)
	(paper "A4")
	(title_block
		(title "04192023_DAF0TMB3IC0_F0TG_MB_C_brd_V02_OCP.brd")
		(comment 1 "Grand Teton / footprints 6852-6853 of 8354")
	)
	(layers
		(0 "F.Cu" signal "TOP")
		(4 "In1.Cu" signal "GND")
		(6 "In2.Cu" signal "IN1")
		(8 "In3.Cu" signal "GND1")
		(10 "In4.Cu" signal "IN2")
		(12 "In5.Cu" signal "GND2")
		(14 "In6.Cu" signal "IN3")
		(16 "In7.Cu" signal "GND3")
		(18 "In8.Cu" signal "VCC")
		(20 "In9.Cu" signal "VCC1")
		(22 "In10.Cu" signal "GND4")
		(24 "In11.Cu" signal "IN4")
		(26 "In12.Cu" signal "GND5")
		(28 "In13.Cu" signal "IN5")
		(30 "In14.Cu" signal "GND6")
		(32 "In15.Cu" signal "IN6")
		(34 "In16.Cu" signal "GND7")
		(2 "B.Cu" signal "BOTTOM")
		(9 "F.Adhes" user "F.Adhesive")
		(11 "B.Adhes" user "B.Adhesive")
		(13 "F.Paste" user "Package Geometry/Pastemask Top")
		(15 "B.Paste" user "Package Geometry/Pastemask Bottom")
		(5 "F.SilkS" user "Ref Des/Silkscreen Top")
		(7 "B.SilkS" user "Ref Des/Silkscreen Bottom")
		(1 "F.Mask" user "Board Geometry/Soldermask Top")
		(3 "B.Mask" user "Board Geometry/Soldermask Bottom")
		(17 "Dwgs.User" user "User.Drawings")
		(19 "Cmts.User" user "User.Comments")
		(21 "Eco1.User" user "User.Eco1")
		(23 "Eco2.User" user "User.Eco2")
		(25 "Edge.Cuts" user "Board Geometry/Outline")
		(27 "Margin" user)
		(31 "F.CrtYd" user "Package Geometry/Place Bound Top")
		(29 "B.CrtYd" user "Package Geometry/Place Bound Bottom")
		(35 "F.Fab" user "Ref Des/Assembly Top")
		(33 "B.Fab" user "Ref Des/Assembly Bottom")
	)
	(footprint ""
		(layer "B.Cu")
		(at 356.057454 -251.78131)
		(property "Reference" "C2589"
			(at 0 0 0)
			(layer "B.SilkS")
			(hide yes)
			(effects
				(font
					(size 1.27 1.27)
				)
				(justify mirror)
			)
		)
		(property "Value" ""
			(at 0 0 0)
			(layer "B.Fab")
			(effects
				(font
					(size 1.27 1.27)
				)
				(justify mirror)
			)
		)
		(duplicate_pad_numbers_are_jumpers no)
		(fp_line
			(start -0.7874 -0.4064)
			(end -0.7874 0.4064)
			(stroke
				(width 0.1524)
				(type default)
			)
			(layer "B.SilkS")
		)
		(fp_line
			(start -0.7874 0.4064)
			(end 0.7874 0.4064)
			(stroke
				(width 0.1524)
				(type default)
			)
			(layer "B.SilkS")
		)
		(fp_line
			(start 0.7874 -0.4064)
			(end -0.7874 -0.4064)
			(stroke
				(width 0.1524)
				(type default)
			)
			(layer "B.SilkS")
		)
		(fp_line
			(start 0.7874 0.4064)
			(end 0.7874 -0.4064)
			(stroke
				(width 0.1524)
				(type default)
			)
			(layer "B.SilkS")
		)
		(fp_line
			(start -0.67945 -0.3048)
			(end -0.67945 0.3048)
			(stroke
				(width 0.1)
				(type default)
			)
			(layer "B.Fab")
		)
		(fp_line
			(start -0.67945 0.3048)
			(end -0.120396 0.3048)
			(stroke
				(width 0.1)
				(type default)
			)
			(layer "B.Fab")
		)
		(fp_line
			(start -0.12065 -0.3048)
			(end -0.67945 -0.3048)
			(stroke
				(width 0.1)
				(type default)
			)
			(layer "B.Fab")
		)
		(fp_line
			(start -0.12065 -0.2794)
			(end -0.12065 -0.3048)
			(stroke
				(width 0.1)
				(type default)
			)
			(layer "B.Fab")
		)
		(fp_line
			(start -0.120396 0.2794)
			(end 0.12065 0.2794)
			(stroke
				(width 0.1)
				(type default)
			)
			(layer "B.Fab")
		)
		(fp_line
			(start -0.120396 0.3048)
			(end -0.120396 0.2794)
			(stroke
				(width 0.1)
				(type default)
			)
			(layer "B.Fab")
		)
		(fp_line
			(start 0.12065 -0.305054)
			(end 0.12065 -0.2794)
			(stroke
				(width 0.1)
				(type default)
			)
			(layer "B.Fab")
		)
		(fp_line
			(start 0.12065 -0.2794)
			(end -0.12065 -0.2794)
			(stroke
				(width 0.1)
				(type default)
			)
			(layer "B.Fab")
		)
		(fp_line
			(start 0.12065 0.2794)
			(end 0.12065 0.3048)
			(stroke
				(width 0.1)
				(type default)
			)
			(layer "B.Fab")
		)
		(fp_line
			(start 0.12065 0.3048)
			(end 0.67945 0.3048)
			(stroke
				(width 0.1)
				(type default)
			)
			(layer "B.Fab")
		)
		(fp_line
			(start 0.67945 -0.305054)
			(end 0.12065 -0.305054)
			(stroke
				(width 0.1)
				(type default)
			)
			(layer "B.Fab")
		)
		(fp_line
			(start 0.67945 0.3048)
			(end 0.67945 -0.305054)
			(stroke
				(width 0.1)
				(type default)
			)
			(layer "B.Fab")
		)
		(pad "1" smd circle
			(at 0.40005 0 180)
			(size 0 0)
			(layers "B.Cu" "B.Mask" "B.Paste")
			(net "PVDDCR_SOC_P0")
		)
		(pad "2" smd circle
			(at -0.40005 0 180)
			(size 0 0)
			(layers "B.Cu" "B.Mask" "B.Paste")
			(net "GND")
		)
	)
	(footprint ""
		(layer "B.Cu")
		(at 180.858922 -20.378166 90)
		(property "Reference" "R2420"
			(at 0 0 90)
			(layer "B.SilkS")
			(hide yes)
			(effects
				(font
					(size 1.27 1.27)
				)
				(justify mirror)
			)
		)
		(property "Value" ""
			(at 0 0 90)
			(layer "B.Fab")
			(effects
				(font
					(size 1.27 1.27)
				)
				(justify mirror)
			)
		)
		(duplicate_pad_numbers_are_jumpers no)
		(fp_line
			(start 0.7874 -0.4064)
			(end -0.7874 -0.4064)
			(stroke
				(width 0.1524)
				(type default)
			)
			(layer "B.SilkS")
		)
		(fp_line
			(start -0.7874 -0.4064)
			(end -0.7874 0.4064)
			(stroke
				(width 0.1524)
				(type default)
			)
			(layer "B.SilkS")
		)
		(fp_line
			(start 0.7874 0.4064)
			(end 0.7874 -0.4064)
			(stroke
				(width 0.1524)
				(type default)
			)
			(layer "B.SilkS")
		)
		(fp_line
			(start -0.7874 0.4064)
			(end 0.7874 0.4064)
			(stroke
				(width 0.1524)
				(type default)
			)
			(layer "B.SilkS")
		)
		(fp_line
			(start 0.67945 -0.305054)
			(end 0.12065 -0.305054)
			(stroke
				(width 0.1)
				(type default)
			)
			(layer "B.Fab")
		)
		(fp_line
			(start 0.12065 -0.305054)
			(end 0.12065 -0.2794)
			(stroke
				(width 0.1)
				(type default)
			)
			(layer "B.Fab")
		)
		(fp_line
			(start -0.12065 -0.3048)
			(end -0.67945 -0.3048)
			(stroke
				(width 0.1)
				(type default)
			)
			(layer "B.Fab")
		)
		(fp_line
			(start -0.67945 -0.3048)
			(end -0.67945 0.3048)
			(stroke
				(width 0.1)
				(type default)
			)
			(layer "B.Fab")
		)
		(fp_line
			(start 0.12065 -0.2794)
			(end -0.12065 -0.2794)
			(stroke
				(width 0.1)
				(type default)
			)
			(layer "B.Fab")
		)
		(fp_line
			(start -0.12065 -0.2794)
			(end -0.12065 -0.3048)
			(stroke
				(width 0.1)
				(type default)
			)
			(layer "B.Fab")
		)
		(fp_line
			(start 0.12065 0.2794)
			(end 0.12065 0.3048)
			(stroke
				(width 0.1)
				(type default)
			)
			(layer "B.Fab")
		)
		(fp_line
			(start -0.120396 0.2794)
			(end 0.12065 0.2794)
			(stroke
				(width 0.1)
				(type default)
			)
			(layer "B.Fab")
		)
		(fp_line
			(start 0.67945 0.3048)
			(end 0.67945 -0.305054)
			(stroke
				(width 0.1)
				(type default)
			)
			(layer "B.Fab")
		)
		(fp_line
			(start 0.12065 0.3048)
			(end 0.67945 0.3048)
			(stroke
				(width 0.1)
				(type default)
			)
			(layer "B.Fab")
		)
		(fp_line
			(start -0.120396 0.3048)
			(end -0.120396 0.2794)
			(stroke
				(width 0.1)
				(type default)
			)
			(layer "B.Fab")
		)
		(fp_line
			(start -0.67945 0.3048)
			(end -0.120396 0.3048)
			(stroke
				(width 0.1)
				(type default)
			)
			(layer "B.Fab")
		)
		(pad "1" smd circle
			(at 0.40005 0 270)
			(size 0 0)
			(layers "B.Cu" "B.Mask" "B.Paste")
			(net "SMB_CPU0_CPU1_APML_SDA")
		)
		(pad "2" smd circle
			(at -0.40005 0 270)
			(size 0 0)
			(layers "B.Cu" "B.Mask" "B.Paste")
			(net "SMB_CPU0_CPU1_APML_SDA_R")
		)
	)
)
